(kicad_pcb
	(version 20241229)
	(generator "pcbnew")
	(generator_version "9.0")
	(general
		(thickness 1.711)
		(legacy_teardrops no)
	)
	(paper "A4")
	(title_block
		(title "Antmicro Baseboard for Jetson AGX Thor")
		(date "2026-02-18")
		(rev "1.1.0")
		(company "Antmicro Ltd")
		(comment 1 "www.antmicro.com")
		(comment 9 "footprints 598-602 of 1170")
	)
	(layers
		(0 "F.Cu" signal)
		(4 "In1.Cu" signal)
		(6 "In2.Cu" signal)
		(8 "In3.Cu" signal)
		(10 "In4.Cu" jumper)
		(12 "In5.Cu" signal)
		(14 "In6.Cu" signal)
		(16 "In7.Cu" signal)
		(18 "In8.Cu" signal)
		(2 "B.Cu" signal)
		(9 "F.Adhes" user "F.Adhesive")
		(11 "B.Adhes" user "B.Adhesive")
		(13 "F.Paste" user)
		(15 "B.Paste" user)
		(5 "F.SilkS" user "F.Silkscreen")
		(7 "B.SilkS" user "B.Silkscreen")
		(1 "F.Mask" user)
		(3 "B.Mask" user)
		(17 "Dwgs.User" user "User.Drawings")
		(19 "Cmts.User" user "User.Comments")
		(21 "Eco1.User" user "User.Eco1")
		(23 "Eco2.User" user "User.Eco2")
		(25 "Edge.Cuts" user)
		(27 "Margin" user)
		(31 "F.CrtYd" user "F.Courtyard")
		(29 "B.CrtYd" user "B.Courtyard")
		(35 "F.Fab" user)
		(33 "B.Fab" user)
	)
	(footprint "antmicro-footprints:C_0603_1608Metric_EIA"
		(layer "F.Cu")
		(at 176.35 113.59 -90)
		(descr "Capacitor SMD 0603, IPC-7351 Density Level A")
		(tags "Capacitor 0603")
		(property "Reference" "C69"
			(at -1.21 7.85 90)
			(layer "F.SilkS")
			(effects
				(font
					(size 0.7 0.7)
					(thickness 0.15)
				)
				(justify right top)
			)
		)
		(property "Value" "C_22u_16V_0603"
			(at -1.42757 1.770288 90)
			(layer "F.Fab")
			(effects
				(font
					(size 0.7 0.7)
					(thickness 0.15)
				)
				(justify right top)
			)
		)
		(property "Datasheet" "https://product.samsungsem.com/mlcc/CL10A226MO7JZN.do"
			(at 0 0 90)
			(layer "F.Fab")
			(hide yes)
			(effects
				(font
					(size 1.27 1.27)
					(thickness 0.15)
				)
			)
		)
		(property "Description" "SMD Multilayer Ceramic Capacitor"
			(at 0 0 90)
			(layer "F.Fab")
			(hide yes)
			(effects
				(font
					(size 1.27 1.27)
					(thickness 0.15)
				)
			)
		)
		(property "Manufacturer" "Samsung Electro-Mechanics"
			(at 0 0 270)
			(unlocked yes)
			(layer "F.Fab")
			(hide yes)
			(effects
				(font
					(size 1 1)
					(thickness 0.15)
				)
			)
		)
		(property "MPN" "CL10A226MO7JZNC"
			(at 0 0 270)
			(unlocked yes)
			(layer "F.Fab")
			(hide yes)
			(effects
				(font
					(size 1 1)
					(thickness 0.15)
				)
			)
		)
		(property "Val" "22u"
			(at 0 0 270)
			(unlocked yes)
			(layer "F.Fab")
			(hide yes)
			(effects
				(font
					(size 1 1)
					(thickness 0.15)
				)
			)
		)
		(property "License" "Apache-2.0"
			(at 0 0 270)
			(unlocked yes)
			(layer "F.Fab")
			(hide yes)
			(effects
				(font
					(size 1 1)
					(thickness 0.15)
				)
			)
		)
		(property "Author" "Antmicro"
			(at 0 0 270)
			(unlocked yes)
			(layer "F.Fab")
			(hide yes)
			(effects
				(font
					(size 1 1)
					(thickness 0.15)
				)
			)
		)
		(property "Voltage" "16V"
			(at 0 0 270)
			(unlocked yes)
			(layer "F.Fab")
			(hide yes)
			(effects
				(font
					(size 1 1)
					(thickness 0.15)
				)
			)
		)
		(property "Dielectric" ""
			(at 0 0 270)
			(unlocked yes)
			(layer "F.Fab")
			(hide yes)
			(effects
				(font
					(size 1 1)
					(thickness 0.15)
				)
			)
		)
		(sheetname "/DCDC/")
		(sheetfile "dcdc.kicad_sch")
		(attr smd)
		(fp_line
			(start -0.15 0.55)
			(end 0.15 0.55)
			(stroke
				(width 0.15)
				(type solid)
			)
			(layer "F.SilkS")
		)
		(fp_line
			(start -0.15 -0.55)
			(end 0.15 -0.55)
			(stroke
				(width 0.15)
				(type solid)
			)
			(layer "F.SilkS")
		)
		(fp_rect
			(start -1.25 -0.65)
			(end 1.25 0.65)
			(stroke
				(width 0.05)
				(type solid)
			)
			(fill no)
			(layer "F.CrtYd")
		)
		(fp_rect
			(start -0.8 -0.45)
			(end 0.8 0.45)
			(stroke
				(width 0.15)
				(type solid)
			)
			(fill no)
			(layer "F.Fab")
		)
		(fp_text user "License: Apache-2.0"
			(at -1.682 5.895 90)
			(layer "F.Fab")
			(effects
				(font
					(size 0.7 0.7)
					(thickness 0.15)
				)
				(justify right top)
			)
		)
		(fp_text user "${REFERENCE}"
			(at -1.682 3.895 90)
			(layer "F.Fab")
			(effects
				(font
					(size 0.7 0.7)
					(thickness 0.15)
				)
				(justify right top)
			)
		)
		(fp_text user "Author: Antmicro"
			(at -1.682 4.894 90)
			(layer "F.Fab")
			(effects
				(font
					(size 0.7 0.7)
					(thickness 0.15)
				)
				(justify right top)
			)
		)
		(pad "1" smd roundrect
			(at -0.7 0 270)
			(size 0.8 1.1)
			(layers "F.Cu" "F.Mask" "F.Paste")
			(roundrect_rratio 0.2)
			(net 1 "GND")
			(pintype "passive")
		)
		(pad "2" smd roundrect
			(at 0.7 0 270)
			(size 0.8 1.1)
			(layers "F.Cu" "F.Mask" "F.Paste")
			(roundrect_rratio 0.2)
			(net 253 "/DCDC/5V_OUT")
			(pintype "passive")
		)
	)
	(footprint "antmicro-footprints:C_0805_2012Metric"
		(layer "F.Cu")
		(at 172.67 146.32 -90)
		(descr "Capacitor SMD 0805")
		(tags "capacitor SMD 0805")
		(property "Reference" "C306"
			(at 1.86 -0.14 90)
			(layer "F.SilkS")
			(effects
				(font
					(size 0.7 0.7)
					(thickness 0.15)
				)
				(justify right top)
			)
		)
		(property "Value" "C_22u_25V_0805"
			(at -2.055717 1.963152 90)
			(layer "F.Fab")
			(effects
				(font
					(size 0.7 0.7)
					(thickness 0.15)
				)
				(justify right top)
			)
		)
		(property "Datasheet" "https://product.samsungsem.com/mlcc/CL21A226MAYNNN.do"
			(at 0 0 90)
			(layer "F.Fab")
			(hide yes)
			(effects
				(font
					(size 1.27 1.27)
					(thickness 0.15)
				)
			)
		)
		(property "Description" "SMT Multilayer Ceramic Capacitor, 22uF, +/-20%, 25V, X5R, 0805 [2012 Metric]"
			(at 0 0 90)
			(layer "F.Fab")
			(hide yes)
			(effects
				(font
					(size 1.27 1.27)
					(thickness 0.15)
				)
			)
		)
		(property "Manufacturer" "Samsung Electro-Mechanics"
			(at 0 0 270)
			(unlocked yes)
			(layer "F.Fab")
			(hide yes)
			(effects
				(font
					(size 1 1)
					(thickness 0.15)
				)
			)
		)
		(property "MPN" "CL21A226MAYNNNE"
			(at 0 0 270)
			(unlocked yes)
			(layer "F.Fab")
			(hide yes)
			(effects
				(font
					(size 1 1)
					(thickness 0.15)
				)
			)
		)
		(property "Val" "22u"
			(at 0 0 270)
			(unlocked yes)
			(layer "F.Fab")
			(hide yes)
			(effects
				(font
					(size 1 1)
					(thickness 0.15)
				)
			)
		)
		(property "License" "Apache-2.0"
			(at 0 0 270)
			(unlocked yes)
			(layer "F.Fab")
			(hide yes)
			(effects
				(font
					(size 1 1)
					(thickness 0.15)
				)
			)
		)
		(property "Author" "Antmicro"
			(at 0 0 270)
			(unlocked yes)
			(layer "F.Fab")
			(hide yes)
			(effects
				(font
					(size 1 1)
					(thickness 0.15)
				)
			)
		)
		(property "Voltage" "25V"
			(at 0 0 270)
			(unlocked yes)
			(layer "F.Fab")
			(hide yes)
			(effects
				(font
					(size 1 1)
					(thickness 0.15)
				)
			)
		)
		(property "Dielectric" "X5R"
			(at 0 0 270)
			(unlocked yes)
			(layer "F.Fab")
			(hide yes)
			(effects
				(font
					(size 1 1)
					(thickness 0.15)
				)
			)
		)
		(property "Public" "False"
			(at 0 0 270)
			(unlocked yes)
			(layer "F.Fab")
			(hide yes)
			(effects
				(font
					(size 1 1)
					(thickness 0.15)
				)
			)
		)
		(sheetname "/DCDC/")
		(sheetfile "dcdc.kicad_sch")
		(attr smd)
		(fp_line
			(start -0.3 0.7)
			(end 0.3 0.7)
			(stroke
				(width 0.15)
				(type solid)
			)
			(layer "F.SilkS")
		)
		(fp_line
			(start -0.3 -0.7)
			(end 0.3 -0.7)
			(stroke
				(width 0.15)
				(type solid)
			)
			(layer "F.SilkS")
		)
		(fp_rect
			(start 1.95 -0.9)
			(end -1.95 0.9)
			(stroke
				(width 0.05)
				(type default)
			)
			(fill no)
			(layer "F.CrtYd")
		)
		(fp_rect
			(start -0.95 -0.675)
			(end 0.95 0.675)
			(stroke
				(width 0.15)
				(type solid)
			)
			(fill no)
			(layer "F.Fab")
		)
		(fp_text user "License: Apache-2.0"
			(at -1.9 4.947 90)
			(layer "F.Fab")
			(effects
				(font
					(size 0.7 0.7)
					(thickness 0.15)
				)
				(justify right top)
			)
		)
		(fp_text user "Author: Antmicro"
			(at -1.9 5.947 90)
			(layer "F.Fab")
			(effects
				(font
					(size 0.7 0.7)
					(thickness 0.15)
				)
				(justify right top)
			)
		)
		(fp_text user "${REFERENCE}"
			(at -1.9 3.947 90)
			(layer "F.Fab")
			(effects
				(font
					(size 0.7 0.7)
					(thickness 0.15)
				)
				(justify right top)
			)
		)
		(pad "1" smd roundrect
			(at -1.1 0 270)
			(size 1.2 1.3)
			(layers "F.Cu" "F.Mask" "F.Paste")
			(roundrect_rratio 0.25)
			(net 1 "GND")
			(pintype "passive")
		)
		(pad "2" smd roundrect
			(at 1.1 0 270)
			(size 1.2 1.3)
			(layers "F.Cu" "F.Mask" "F.Paste")
			(roundrect_rratio 0.25)
			(net 880 "/DCDC/12V_OUT")
			(pintype "passive")
		)
	)
	(footprint "antmicro-footprints:R_0402_1005Metric"
		(layer "F.Cu")
		(at 214.9 98.2 -90)
		(descr "Resistor SMD 0402")
		(tags "resistor SMD 0402")
		(property "Reference" "R277"
			(at -1.1 3.4 90)
			(layer "F.SilkS")
			(effects
				(font
					(size 0.7 0.7)
					(thickness 0.15)
				)
				(justify right top)
			)
		)
		(property "Value" "R_0R_0402"
			(at -1.011843 1.772046 90)
			(layer "F.Fab")
			(effects
				(font
					(size 0.7 0.7)
					(thickness 0.15)
				)
				(justify right top)
			)
		)
		(property "Datasheet" "https://industrial.panasonic.com/cdbs/www-data/pdf/RDA0000/AOA0000C301.pdf"
			(at 0 0 90)
			(layer "F.Fab")
			(hide yes)
			(effects
				(font
					(size 1.27 1.27)
					(thickness 0.15)
				)
			)
		)
		(property "Description" "SMD Chip Resistor, Jumper, 0 ohm, 100 mW, 0402 [1005 Metric], Thick Film, General Purpose"
			(at 0 0 90)
			(layer "F.Fab")
			(hide yes)
			(effects
				(font
					(size 1.27 1.27)
					(thickness 0.15)
				)
			)
		)
		(property "Manufacturer" "Panasonic"
			(at 0 0 270)
			(unlocked yes)
			(layer "F.Fab")
			(hide yes)
			(effects
				(font
					(size 1 1)
					(thickness 0.15)
				)
			)
		)
		(property "MPN" "ERJ2GE0R00X"
			(at 0 0 270)
			(unlocked yes)
			(layer "F.Fab")
			(hide yes)
			(effects
				(font
					(size 1 1)
					(thickness 0.15)
				)
			)
		)
		(property "Val" "0R"
			(at 0 0 270)
			(unlocked yes)
			(layer "F.Fab")
			(hide yes)
			(effects
				(font
					(size 1 1)
					(thickness 0.15)
				)
			)
		)
		(property "License" "Apache-2.0"
			(at 0 0 270)
			(unlocked yes)
			(layer "F.Fab")
			(hide yes)
			(effects
				(font
					(size 1 1)
					(thickness 0.15)
				)
			)
		)
		(property "Author" "Antmicro"
			(at 0 0 270)
			(unlocked yes)
			(layer "F.Fab")
			(hide yes)
			(effects
				(font
					(size 1 1)
					(thickness 0.15)
				)
			)
		)
		(property "Tolerance" "~"
			(at 0 0 270)
			(unlocked yes)
			(layer "F.Fab")
			(hide yes)
			(effects
				(font
					(size 1 1)
					(thickness 0.15)
				)
			)
		)
		(property "Current" "1A"
			(at 0 0 270)
			(unlocked yes)
			(layer "F.Fab")
			(hide yes)
			(effects
				(font
					(size 1 1)
					(thickness 0.15)
				)
			)
		)
		(sheetname "/Recovery USB/")
		(sheetfile "recovery_usb.kicad_sch")
		(attr smd)
		(fp_poly
			(pts
				(xy -0.925 -0.47) (xy 0.925 -0.47) (xy 0.925 0.47) (xy -0.925 0.47)
			)
			(stroke
				(width 0.05)
				(type default)
			)
			(fill no)
			(layer "F.CrtYd")
		)
		(fp_poly
			(pts
				(xy -0.5 -0.25) (xy 0.5 -0.25) (xy 0.5 0.25) (xy -0.5 0.25)
			)
			(stroke
				(width 0.15)
				(type solid)
			)
			(fill no)
			(layer "F.Fab")
		)
		(fp_text user "License: Apache-2.0"
			(at -0.949999 5.169 90)
			(layer "F.Fab")
			(effects
				(font
					(size 0.7 0.7)
					(thickness 0.15)
				)
				(justify right top)
			)
		)
		(fp_text user "Author: Antmicro"
			(at -0.95 4.169 90)
			(layer "F.Fab")
			(effects
				(font
					(size 0.7 0.7)
					(thickness 0.15)
				)
				(justify right top)
			)
		)
		(fp_text user "${REFERENCE}"
			(at -0.95 3.168 90)
			(layer "F.Fab")
			(effects
				(font
					(size 0.7 0.7)
					(thickness 0.15)
				)
				(justify right top)
			)
		)
		(pad "1" smd roundrect
			(at -0.48 0 270)
			(size 0.59 0.64)
			(layers "F.Cu" "F.Mask" "F.Paste")
			(roundrect_rratio 0.25)
			(net 1 "GND")
			(pintype "passive")
		)
		(pad "2" smd roundrect
			(at 0.48 0 270)
			(size 0.59 0.64)
			(layers "F.Cu" "F.Mask" "F.Paste")
			(roundrect_rratio 0.25)
			(net 1022 "/Recovery USB/~{USBC2_EN_CC}")
			(pintype "passive")
		)
	)
	(footprint "antmicro-footprints:C_0402_1005Metric"
		(layer "F.Cu")
		(at 89.1 93.1)
		(descr "Capacitor SMD 0402")
		(tags "capacitor SMD 0402")
		(property "Reference" "C339"
			(at -3.82 0.45 0)
			(layer "F.SilkS")
			(effects
				(font
					(size 0.7 0.7)
					(thickness 0.15)
				)
				(justify left bottom)
			)
		)
		(property "Value" "C_100n_0402"
			(at -1.022927 2.155213 0)
			(layer "F.Fab")
			(effects
				(font
					(size 0.7 0.7)
					(thickness 0.15)
				)
				(justify left bottom)
			)
		)
		(property "Datasheet" "https://www.murata.com/products/productdetail?partno=GRM155R61H104KE14%23"
			(at 0 0 0)
			(layer "F.Fab")
			(hide yes)
			(effects
				(font
					(size 1.27 1.27)
					(thickness 0.15)
				)
			)
		)
		(property "Description" "SMD Multilayer Ceramic Capacitor, 0.1 µF, 50 V, 0402 [1005 Metric], ± 10%, X5R, GRM Series"
			(at 0 0 0)
			(layer "F.Fab")
			(hide yes)
			(effects
				(font
					(size 1.27 1.27)
					(thickness 0.15)
				)
			)
		)
		(property "Manufacturer" "Murata"
			(at 0 0 0)
			(unlocked yes)
			(layer "F.Fab")
			(hide yes)
			(effects
				(font
					(size 1 1)
					(thickness 0.15)
				)
			)
		)
		(property "MPN" "GRM155R61H104KE14D"
			(at 0 0 0)
			(unlocked yes)
			(layer "F.Fab")
			(hide yes)
			(effects
				(font
					(size 1 1)
					(thickness 0.15)
				)
			)
		)
		(property "Val" "100n"
			(at 0 0 0)
			(unlocked yes)
			(layer "F.Fab")
			(hide yes)
			(effects
				(font
					(size 1 1)
					(thickness 0.15)
				)
			)
		)
		(property "License" "Apache-2.0"
			(at 0 0 0)
			(unlocked yes)
			(layer "F.Fab")
			(hide yes)
			(effects
				(font
					(size 1 1)
					(thickness 0.15)
				)
			)
		)
		(property "Author" "Antmicro"
			(at 0 0 0)
			(unlocked yes)
			(layer "F.Fab")
			(hide yes)
			(effects
				(font
					(size 1 1)
					(thickness 0.15)
				)
			)
		)
		(property "Voltage" "50V"
			(at 0 0 0)
			(unlocked yes)
			(layer "F.Fab")
			(hide yes)
			(effects
				(font
					(size 1 1)
					(thickness 0.15)
				)
			)
		)
		(property "Dielectric" "X5R"
			(at 0 0 0)
			(unlocked yes)
			(layer "F.Fab")
			(hide yes)
			(effects
				(font
					(size 1 1)
					(thickness 0.15)
				)
			)
		)
		(sheetname "/SoM_IO2/")
		(sheetfile "som_io2.kicad_sch")
		(attr smd)
		(fp_rect
			(start -0.925 -0.47)
			(end 0.925 0.47)
			(stroke
				(width 0.05)
				(type default)
			)
			(fill no)
			(layer "F.CrtYd")
		)
		(fp_line
			(start -0.494 -0.25)
			(end 0.504 -0.25)
			(stroke
				(width 0.15)
				(type solid)
			)
			(layer "F.Fab")
		)
		(fp_line
			(start -0.494 0.248)
			(end -0.494 -0.25)
			(stroke
				(width 0.15)
				(type solid)
			)
			(layer "F.Fab")
		)
		(fp_line
			(start 0.504 -0.25)
			(end 0.504 0.248)
			(stroke
				(width 0.15)
				(type solid)
			)
			(layer "F.Fab")
		)
		(fp_line
			(start 0.504 0.248)
			(end -0.494 0.248)
			(stroke
				(width 0.15)
				(type solid)
			)
			(layer "F.Fab")
		)
		(fp_text user "Author: Antmicro"
			(at -0.939 3.399 0)
			(layer "F.Fab")
			(effects
				(font
					(size 0.7 0.7)
					(thickness 0.15)
				)
				(justify left bottom)
			)
		)
		(fp_text user "${REFERENCE}"
			(at -0.939 4.599 0)
			(layer "F.Fab")
			(effects
				(font
					(size 0.7 0.7)
					(thickness 0.15)
				)
				(justify left bottom)
			)
		)
		(fp_text user "License: Apache-2.0"
			(at -0.939 5.799 0)
			(layer "F.Fab")
			(effects
				(font
					(size 0.7 0.7)
					(thickness 0.15)
				)
				(justify left bottom)
			)
		)
		(pad "1" smd roundrect
			(at -0.48 0)
			(size 0.59 0.64)
			(layers "F.Cu" "F.Mask" "F.Paste")
			(roundrect_rratio 0.25)
			(net 744 "/Expansion connector/DP2.TX1-")
			(pintype "passive")
		)
		(pad "2" smd roundrect
			(at 0.48 0)
			(size 0.59 0.64)
			(layers "F.Cu" "F.Mask" "F.Paste")
			(roundrect_rratio 0.25)
			(net 1259 "/SoM_IO2/DP2.TX1_C-")
			(pintype "passive")
		)
	)
	(footprint "antmicro-footprints:TP_SMD_0.75mm"
		(layer "F.Cu")
		(at 175.25 57.175)
		(property "Reference" "TP75"
			(at -0.585 2.095 90)
			(layer "F.SilkS")
			(hide yes)
			(effects
				(font
					(size 0.7 0.7)
					(thickness 0.15)
				)
				(justify left bottom)
			)
		)
		(property "Value" "TP_0.75mm_SMD"
			(at 0 1.2 0)
			(layer "F.Fab")
			(effects
				(font
					(size 0.7 0.7)
					(thickness 0.15)
				)
				(justify left bottom)
			)
		)
		(property "Description" "SMT test point"
			(at 0 0 0)
			(layer "F.Fab")
			(hide yes)
			(effects
				(font
					(size 1.27 1.27)
					(thickness 0.15)
				)
			)
		)
		(property "MPN" ""
			(at 0 0 0)
			(unlocked yes)
			(layer "F.Fab")
			(hide yes)
			(effects
				(font
					(size 1 1)
					(thickness 0.15)
				)
			)
		)
		(property "Manufacturer" ""
			(at 0 0 0)
			(unlocked yes)
			(layer "F.Fab")
			(hide yes)
			(effects
				(font
					(size 1 1)
					(thickness 0.15)
				)
			)
		)
		(property "Author" "Antmicro"
			(at 0 0 0)
			(unlocked yes)
			(layer "F.Fab")
			(hide yes)
			(effects
				(font
					(size 1 1)
					(thickness 0.15)
				)
			)
		)
		(property "License" "Apache-2.0"
			(at 0 0 0)
			(unlocked yes)
			(layer "F.Fab")
			(hide yes)
			(effects
				(font
					(size 1 1)
					(thickness 0.15)
				)
			)
		)
		(sheetname "/Power/")
		(sheetfile "power.kicad_sch")
		(attr exclude_from_pos_files exclude_from_bom)
		(fp_circle
			(center 0 0)
			(end 0.475 0)
			(stroke
				(width 0.05)
				(type default)
			)
			(fill no)
			(layer "F.CrtYd")
		)
		(fp_text user "Author: Antmicro"
			(at -0.4 3.901 0)
			(layer "F.Fab")
			(effects
				(font
					(size 0.7 0.7)
					(thickness 0.15)
				)
				(justify left bottom)
			)
		)
		(fp_text user "${REFERENCE}"
			(at -0.4 2.7 0)
			(layer "F.Fab")
			(effects
				(font
					(size 0.7 0.7)
					(thickness 0.15)
				)
				(justify left bottom)
			)
		)
		(fp_text user "License: Apache-2.0"
			(at -0.4 5.101 0)
			(layer "F.Fab")
			(effects
				(font
					(size 0.7 0.7)
					(thickness 0.15)
				)
				(justify left bottom)
			)
		)
		(pad "1" smd circle
			(at 0 0)
			(size 0.75 0.75)
			(layers "F.Cu" "F.Mask")
			(net 213 "+5V_SOM")
			(pinfunction "1")
			(pintype "passive")
		)
	)
)
